(kicad_pcb
	(version 20260206)
	(generator "pcbnew")
	(generator_version "10.0")
	(general
		(thickness 1.6)
		(legacy_teardrops no)
	)
	(paper "A4")
	(title_block
		(title "03242023_DA0F0TMBIJ0_F0T_Motherboard_J_brd_V01_OCP.brd")
		(comment 1 "Grand Teton / footprints 3007-3013 of 6105")
	)
	(layers
		(0 "F.Cu" signal "TOP")
		(4 "In1.Cu" signal "GND")
		(6 "In2.Cu" signal "IN1")
		(8 "In3.Cu" signal "GND1")
		(10 "In4.Cu" signal "IN2")
		(12 "In5.Cu" signal "GND2")
		(14 "In6.Cu" signal "IN3")
		(16 "In7.Cu" signal "GND3")
		(18 "In8.Cu" signal "VCC")
		(20 "In9.Cu" signal "VCC1")
		(22 "In10.Cu" signal "GND4")
		(24 "In11.Cu" signal "IN4")
		(26 "In12.Cu" signal "GND5")
		(28 "In13.Cu" signal "IN5")
		(30 "In14.Cu" signal "GND6")
		(32 "In15.Cu" signal "IN6")
		(34 "In16.Cu" signal "GND7")
		(2 "B.Cu" signal "BOTTOM")
		(9 "F.Adhes" user "F.Adhesive")
		(11 "B.Adhes" user "B.Adhesive")
		(13 "F.Paste" user "Package Geometry/Pastemask Top")
		(15 "B.Paste" user "Package Geometry/Pastemask Bottom")
		(5 "F.SilkS" user "Ref Des/Silkscreen Top")
		(7 "B.SilkS" user "Ref Des/Silkscreen Bottom")
		(1 "F.Mask" user "Board Geometry/Soldermask Top")
		(3 "B.Mask" user "Board Geometry/Soldermask Bottom")
		(17 "Dwgs.User" user "User.Drawings")
		(19 "Cmts.User" user "User.Comments")
		(21 "Eco1.User" user "User.Eco1")
		(23 "Eco2.User" user "User.Eco2")
		(25 "Edge.Cuts" user "Board Geometry/Outline")
		(27 "Margin" user)
		(31 "F.CrtYd" user "Package Geometry/Place Bound Top")
		(29 "B.CrtYd" user "Package Geometry/Place Bound Bottom")
		(35 "F.Fab" user "Ref Des/Assembly Top")
		(33 "B.Fab" user "Ref Des/Assembly Bottom")
	)
	(footprint ""
		(layer "F.Cu")
		(at 355.8286 -404.876 180)
		(property "Reference" "R4731"
			(at 0 0 180)
			(layer "F.SilkS")
			(hide yes)
			(effects
				(font
					(size 1.27 1.27)
				)
			)
		)
		(property "Value" ""
			(at 0 0 180)
			(layer "F.Fab")
			(effects
				(font
					(size 1.27 1.27)
				)
			)
		)
		(duplicate_pad_numbers_are_jumpers no)
		(fp_line
			(start 0.7874 0.4064)
			(end -0.7874 0.4064)
			(stroke
				(width 0.1524)
				(type default)
			)
			(layer "F.SilkS")
		)
		(fp_line
			(start 0.7874 -0.4064)
			(end 0.7874 0.4064)
			(stroke
				(width 0.1524)
				(type default)
			)
			(layer "F.SilkS")
		)
		(fp_line
			(start -0.7874 0.4064)
			(end -0.7874 -0.4064)
			(stroke
				(width 0.1524)
				(type default)
			)
			(layer "F.SilkS")
		)
		(fp_line
			(start -0.7874 -0.4064)
			(end 0.7874 -0.4064)
			(stroke
				(width 0.1524)
				(type default)
			)
			(layer "F.SilkS")
		)
		(fp_line
			(start 0.67945 0.3048)
			(end 0.120396 0.3048)
			(stroke
				(width 0.1)
				(type default)
			)
			(layer "F.Fab")
		)
		(fp_line
			(start 0.67945 -0.3048)
			(end 0.67945 0.3048)
			(stroke
				(width 0.1)
				(type default)
			)
			(layer "F.Fab")
		)
		(fp_line
			(start 0.12065 -0.2794)
			(end 0.12065 -0.3048)
			(stroke
				(width 0.1)
				(type default)
			)
			(layer "F.Fab")
		)
		(fp_line
			(start 0.12065 -0.3048)
			(end 0.67945 -0.3048)
			(stroke
				(width 0.1)
				(type default)
			)
			(layer "F.Fab")
		)
		(fp_line
			(start 0.120396 0.3048)
			(end 0.120396 0.2794)
			(stroke
				(width 0.1)
				(type default)
			)
			(layer "F.Fab")
		)
		(fp_line
			(start 0.120396 0.2794)
			(end -0.12065 0.2794)
			(stroke
				(width 0.1)
				(type default)
			)
			(layer "F.Fab")
		)
		(fp_line
			(start -0.12065 0.3048)
			(end -0.67945 0.3048)
			(stroke
				(width 0.1)
				(type default)
			)
			(layer "F.Fab")
		)
		(fp_line
			(start -0.12065 0.2794)
			(end -0.12065 0.3048)
			(stroke
				(width 0.1)
				(type default)
			)
			(layer "F.Fab")
		)
		(fp_line
			(start -0.12065 -0.2794)
			(end 0.12065 -0.2794)
			(stroke
				(width 0.1)
				(type default)
			)
			(layer "F.Fab")
		)
		(fp_line
			(start -0.12065 -0.305054)
			(end -0.12065 -0.2794)
			(stroke
				(width 0.1)
				(type default)
			)
			(layer "F.Fab")
		)
		(fp_line
			(start -0.67945 0.3048)
			(end -0.67945 -0.305054)
			(stroke
				(width 0.1)
				(type default)
			)
			(layer "F.Fab")
		)
		(fp_line
			(start -0.67945 -0.305054)
			(end -0.12065 -0.305054)
			(stroke
				(width 0.1)
				(type default)
			)
			(layer "F.Fab")
		)
		(pad "1" smd circle
			(at -0.40005 0 180)
			(size 0 0)
			(layers "F.Cu" "F.Mask" "F.Paste")
			(net "PRSNT_CABLE_SWB_B2_N")
		)
		(pad "2" smd circle
			(at 0.40005 0 180)
			(size 0 0)
			(layers "F.Cu" "F.Mask" "F.Paste")
			(net "GND")
		)
	)
	(footprint ""
		(layer "F.Cu")
		(at 207.074008 -402.994622 90)
		(property "Reference" "PC2181"
			(at 0 0 90)
			(layer "F.SilkS")
			(hide yes)
			(effects
				(font
					(size 1.27 1.27)
				)
			)
		)
		(property "Value" ""
			(at 0 0 90)
			(layer "F.Fab")
			(effects
				(font
					(size 1.27 1.27)
				)
			)
		)
		(duplicate_pad_numbers_are_jumpers no)
		(fp_line
			(start 0.7874 -0.4064)
			(end 0.7874 0.4064)
			(stroke
				(width 0.1524)
				(type default)
			)
			(layer "F.SilkS")
		)
		(fp_line
			(start -0.7874 -0.4064)
			(end 0.7874 -0.4064)
			(stroke
				(width 0.1524)
				(type default)
			)
			(layer "F.SilkS")
		)
		(fp_line
			(start 0.7874 0.4064)
			(end -0.7874 0.4064)
			(stroke
				(width 0.1524)
				(type default)
			)
			(layer "F.SilkS")
		)
		(fp_line
			(start -0.7874 0.4064)
			(end -0.7874 -0.4064)
			(stroke
				(width 0.1524)
				(type default)
			)
			(layer "F.SilkS")
		)
		(fp_line
			(start -0.12065 -0.305054)
			(end -0.12065 -0.2794)
			(stroke
				(width 0.1)
				(type default)
			)
			(layer "F.Fab")
		)
		(fp_line
			(start -0.67945 -0.305054)
			(end -0.12065 -0.305054)
			(stroke
				(width 0.1)
				(type default)
			)
			(layer "F.Fab")
		)
		(fp_line
			(start 0.67945 -0.3048)
			(end 0.67945 0.3048)
			(stroke
				(width 0.1)
				(type default)
			)
			(layer "F.Fab")
		)
		(fp_line
			(start 0.12065 -0.3048)
			(end 0.67945 -0.3048)
			(stroke
				(width 0.1)
				(type default)
			)
			(layer "F.Fab")
		)
		(fp_line
			(start 0.12065 -0.2794)
			(end 0.12065 -0.3048)
			(stroke
				(width 0.1)
				(type default)
			)
			(layer "F.Fab")
		)
		(fp_line
			(start -0.12065 -0.2794)
			(end 0.12065 -0.2794)
			(stroke
				(width 0.1)
				(type default)
			)
			(layer "F.Fab")
		)
		(fp_line
			(start 0.120396 0.2794)
			(end -0.12065 0.2794)
			(stroke
				(width 0.1)
				(type default)
			)
			(layer "F.Fab")
		)
		(fp_line
			(start -0.12065 0.2794)
			(end -0.12065 0.3048)
			(stroke
				(width 0.1)
				(type default)
			)
			(layer "F.Fab")
		)
		(fp_line
			(start 0.67945 0.3048)
			(end 0.120396 0.3048)
			(stroke
				(width 0.1)
				(type default)
			)
			(layer "F.Fab")
		)
		(fp_line
			(start 0.120396 0.3048)
			(end 0.120396 0.2794)
			(stroke
				(width 0.1)
				(type default)
			)
			(layer "F.Fab")
		)
		(fp_line
			(start -0.12065 0.3048)
			(end -0.67945 0.3048)
			(stroke
				(width 0.1)
				(type default)
			)
			(layer "F.Fab")
		)
		(fp_line
			(start -0.67945 0.3048)
			(end -0.67945 -0.305054)
			(stroke
				(width 0.1)
				(type default)
			)
			(layer "F.Fab")
		)
		(pad "1" smd circle
			(at -0.40005 0 90)
			(size 0 0)
			(layers "F.Cu" "F.Mask" "F.Paste")
			(net "HSC_VDD_R_2")
		)
		(pad "2" smd circle
			(at 0.40005 0 90)
			(size 0 0)
			(layers "F.Cu" "F.Mask" "F.Paste")
			(net "AGND_HSC")
		)
	)
	(footprint ""
		(layer "F.Cu")
		(at 373.736616 -366.581944 90)
		(property "Reference" "PL118"
			(at 4.647438 -1.728724 0)
			(unlocked yes)
			(layer "F.SilkS")
			(effects
				(font
					(size 0.7874 0.5842)
					(thickness 0.1524)
				)
				(justify left)
			)
		)
		(property "Value" ""
			(at 0 0 90)
			(layer "F.Fab")
			(effects
				(font
					(size 1.27 1.27)
				)
			)
		)
		(duplicate_pad_numbers_are_jumpers no)
		(fp_line
			(start 3.64998 -3.350006)
			(end 3.64998 -1.8034)
			(stroke
				(width 0.1524)
				(type default)
			)
			(layer "F.SilkS")
		)
		(fp_line
			(start -3.6576 -3.350006)
			(end 3.64998 -3.350006)
			(stroke
				(width 0.1524)
				(type default)
			)
			(layer "F.SilkS")
		)
		(fp_line
			(start -3.64998 -1.8034)
			(end -3.64998 -3.350006)
			(stroke
				(width 0.1524)
				(type default)
			)
			(layer "F.SilkS")
		)
		(fp_line
			(start 3.64998 1.8034)
			(end 3.64998 3.350006)
			(stroke
				(width 0.1524)
				(type default)
			)
			(layer "F.SilkS")
		)
		(fp_line
			(start 3.64998 3.350006)
			(end -3.64998 3.350006)
			(stroke
				(width 0.1524)
				(type default)
			)
			(layer "F.SilkS")
		)
		(fp_line
			(start -3.64998 3.350006)
			(end -3.64998 1.8288)
			(stroke
				(width 0.1524)
				(type default)
			)
			(layer "F.SilkS")
		)
		(fp_line
			(start 3.64998 -3.350006)
			(end 3.64998 3.350006)
			(stroke
				(width 0.1)
				(type default)
			)
			(layer "F.Fab")
		)
		(fp_line
			(start -3.64998 -3.350006)
			(end 3.64998 -3.350006)
			(stroke
				(width 0.1)
				(type default)
			)
			(layer "F.Fab")
		)
		(fp_line
			(start 3.64998 3.350006)
			(end -3.64998 3.350006)
			(stroke
				(width 0.1)
				(type default)
			)
			(layer "F.Fab")
		)
		(fp_line
			(start -3.64998 3.350006)
			(end -3.64998 -3.350006)
			(stroke
				(width 0.1)
				(type default)
			)
			(layer "F.Fab")
		)
		(pad "1" smd rect
			(at -2.92481 0 90)
			(size 2.15392 3.302)
			(layers "F.Cu" "F.Mask" "F.Paste")
			(net "SW_PVPP_HBM_CPU0_SW")
		)
		(pad "2" smd rect
			(at 2.92481 0 90)
			(size 2.15392 3.302)
			(layers "F.Cu" "F.Mask" "F.Paste")
			(net "PVPP_HBM_CPU0")
		)
	)
	(footprint ""
		(layer "F.Cu")
		(at 162.179 -20.665948 -90)
		(property "Reference" "R4508"
			(at 0 0 270)
			(layer "F.SilkS")
			(hide yes)
			(effects
				(font
					(size 1.27 1.27)
				)
			)
		)
		(property "Value" ""
			(at 0 0 270)
			(layer "F.Fab")
			(effects
				(font
					(size 1.27 1.27)
				)
			)
		)
		(duplicate_pad_numbers_are_jumpers no)
		(fp_line
			(start -0.7874 0.4064)
			(end -0.7874 -0.4064)
			(stroke
				(width 0.1524)
				(type default)
			)
			(layer "F.SilkS")
		)
		(fp_line
			(start 0.7874 0.4064)
			(end -0.7874 0.4064)
			(stroke
				(width 0.1524)
				(type default)
			)
			(layer "F.SilkS")
		)
		(fp_line
			(start -0.7874 -0.4064)
			(end 0.7874 -0.4064)
			(stroke
				(width 0.1524)
				(type default)
			)
			(layer "F.SilkS")
		)
		(fp_line
			(start 0.7874 -0.4064)
			(end 0.7874 0.4064)
			(stroke
				(width 0.1524)
				(type default)
			)
			(layer "F.SilkS")
		)
		(fp_line
			(start -0.67945 0.3048)
			(end -0.67945 -0.305054)
			(stroke
				(width 0.1)
				(type default)
			)
			(layer "F.Fab")
		)
		(fp_line
			(start -0.12065 0.3048)
			(end -0.67945 0.3048)
			(stroke
				(width 0.1)
				(type default)
			)
			(layer "F.Fab")
		)
		(fp_line
			(start 0.120396 0.3048)
			(end 0.120396 0.2794)
			(stroke
				(width 0.1)
				(type default)
			)
			(layer "F.Fab")
		)
		(fp_line
			(start 0.67945 0.3048)
			(end 0.120396 0.3048)
			(stroke
				(width 0.1)
				(type default)
			)
			(layer "F.Fab")
		)
		(fp_line
			(start -0.12065 0.2794)
			(end -0.12065 0.3048)
			(stroke
				(width 0.1)
				(type default)
			)
			(layer "F.Fab")
		)
		(fp_line
			(start 0.120396 0.2794)
			(end -0.12065 0.2794)
			(stroke
				(width 0.1)
				(type default)
			)
			(layer "F.Fab")
		)
		(fp_line
			(start -0.12065 -0.2794)
			(end 0.12065 -0.2794)
			(stroke
				(width 0.1)
				(type default)
			)
			(layer "F.Fab")
		)
		(fp_line
			(start 0.12065 -0.2794)
			(end 0.12065 -0.3048)
			(stroke
				(width 0.1)
				(type default)
			)
			(layer "F.Fab")
		)
		(fp_line
			(start 0.12065 -0.3048)
			(end 0.67945 -0.3048)
			(stroke
				(width 0.1)
				(type default)
			)
			(layer "F.Fab")
		)
		(fp_line
			(start 0.67945 -0.3048)
			(end 0.67945 0.3048)
			(stroke
				(width 0.1)
				(type default)
			)
			(layer "F.Fab")
		)
		(fp_line
			(start -0.67945 -0.305054)
			(end -0.12065 -0.305054)
			(stroke
				(width 0.1)
				(type default)
			)
			(layer "F.Fab")
		)
		(fp_line
			(start -0.12065 -0.305054)
			(end -0.12065 -0.2794)
			(stroke
				(width 0.1)
				(type default)
			)
			(layer "F.Fab")
		)
		(pad "1" smd circle
			(at -0.40005 0 270)
			(size 0 0)
			(layers "F.Cu" "F.Mask" "F.Paste")
			(net "SMB_1_PLD_3V3AUX_SCL")
		)
		(pad "2" smd circle
			(at 0.40005 0 270)
			(size 0 0)
			(layers "F.Cu" "F.Mask" "F.Paste")
			(net "SMB_1_PLD_3V3AUX_SCL_R3")
		)
	)
	(footprint ""
		(layer "F.Cu")
		(at 466.68309 -46.408848)
		(property "Reference" "C1175"
			(at 0 0 0)
			(layer "F.SilkS")
			(hide yes)
			(effects
				(font
					(size 1.27 1.27)
				)
			)
		)
		(property "Value" ""
			(at 0 0 0)
			(layer "F.Fab")
			(effects
				(font
					(size 1.27 1.27)
				)
			)
		)
		(duplicate_pad_numbers_are_jumpers no)
		(fp_line
			(start -0.7874 -0.4064)
			(end 0.7874 -0.4064)
			(stroke
				(width 0.1524)
				(type default)
			)
			(layer "F.SilkS")
		)
		(fp_line
			(start -0.7874 0.4064)
			(end -0.7874 -0.4064)
			(stroke
				(width 0.1524)
				(type default)
			)
			(layer "F.SilkS")
		)
		(fp_line
			(start 0.7874 -0.4064)
			(end 0.7874 0.4064)
			(stroke
				(width 0.1524)
				(type default)
			)
			(layer "F.SilkS")
		)
		(fp_line
			(start 0.7874 0.4064)
			(end -0.7874 0.4064)
			(stroke
				(width 0.1524)
				(type default)
			)
			(layer "F.SilkS")
		)
		(fp_line
			(start -0.67945 -0.305054)
			(end -0.12065 -0.305054)
			(stroke
				(width 0.1)
				(type default)
			)
			(layer "F.Fab")
		)
		(fp_line
			(start -0.67945 0.3048)
			(end -0.67945 -0.305054)
			(stroke
				(width 0.1)
				(type default)
			)
			(layer "F.Fab")
		)
		(fp_line
			(start -0.12065 -0.305054)
			(end -0.12065 -0.2794)
			(stroke
				(width 0.1)
				(type default)
			)
			(layer "F.Fab")
		)
		(fp_line
			(start -0.12065 -0.2794)
			(end 0.12065 -0.2794)
			(stroke
				(width 0.1)
				(type default)
			)
			(layer "F.Fab")
		)
		(fp_line
			(start -0.12065 0.2794)
			(end -0.12065 0.3048)
			(stroke
				(width 0.1)
				(type default)
			)
			(layer "F.Fab")
		)
		(fp_line
			(start -0.12065 0.3048)
			(end -0.67945 0.3048)
			(stroke
				(width 0.1)
				(type default)
			)
			(layer "F.Fab")
		)
		(fp_line
			(start 0.120396 0.2794)
			(end -0.12065 0.2794)
			(stroke
				(width 0.1)
				(type default)
			)
			(layer "F.Fab")
		)
		(fp_line
			(start 0.120396 0.3048)
			(end 0.120396 0.2794)
			(stroke
				(width 0.1)
				(type default)
			)
			(layer "F.Fab")
		)
		(fp_line
			(start 0.12065 -0.3048)
			(end 0.67945 -0.3048)
			(stroke
				(width 0.1)
				(type default)
			)
			(layer "F.Fab")
		)
		(fp_line
			(start 0.12065 -0.2794)
			(end 0.12065 -0.3048)
			(stroke
				(width 0.1)
				(type default)
			)
			(layer "F.Fab")
		)
		(fp_line
			(start 0.67945 -0.3048)
			(end 0.67945 0.3048)
			(stroke
				(width 0.1)
				(type default)
			)
			(layer "F.Fab")
		)
		(fp_line
			(start 0.67945 0.3048)
			(end 0.120396 0.3048)
			(stroke
				(width 0.1)
				(type default)
			)
			(layer "F.Fab")
		)
		(pad "1" smd circle
			(at -0.40005 0)
			(size 0 0)
			(layers "F.Cu" "F.Mask" "F.Paste")
			(net "P3V3_AUX")
		)
		(pad "2" smd circle
			(at 0.40005 0)
			(size 0 0)
			(layers "F.Cu" "F.Mask" "F.Paste")
			(net "GND")
		)
	)
	(footprint ""
		(layer "F.Cu")
		(at 374.336056 -354.844858)
		(property "Reference" "PC831"
			(at 0 0 0)
			(layer "F.SilkS")
			(hide yes)
			(effects
				(font
					(size 1.27 1.27)
				)
			)
		)
		(property "Value" ""
			(at 0 0 0)
			(layer "F.Fab")
			(effects
				(font
					(size 1.27 1.27)
				)
			)
		)
		(duplicate_pad_numbers_are_jumpers no)
		(fp_line
			(start -1.524 -0.762)
			(end 1.524 -0.762)
			(stroke
				(width 0.1524)
				(type default)
			)
			(layer "F.SilkS")
		)
		(fp_line
			(start -1.524 0.762)
			(end -1.524 -0.762)
			(stroke
				(width 0.1524)
				(type default)
			)
			(layer "F.SilkS")
		)
		(fp_line
			(start 1.524 -0.762)
			(end 1.524 0.762)
			(stroke
				(width 0.1524)
				(type default)
			)
			(layer "F.SilkS")
		)
		(fp_line
			(start 1.524 0.762)
			(end -1.524 0.762)
			(stroke
				(width 0.1524)
				(type default)
			)
			(layer "F.SilkS")
		)
		(fp_line
			(start -1.1049 -0.724916)
			(end -1.1049 0.724916)
			(stroke
				(width 0.1)
				(type default)
			)
			(layer "F.Fab")
		)
		(fp_line
			(start -1.1049 0.724916)
			(end 1.1049 0.724916)
			(stroke
				(width 0.1)
				(type default)
			)
			(layer "F.Fab")
		)
		(fp_line
			(start 1.1049 -0.724916)
			(end -1.1049 -0.724916)
			(stroke
				(width 0.1)
				(type default)
			)
			(layer "F.Fab")
		)
		(fp_line
			(start 1.1049 0.724916)
			(end 1.1049 -0.724916)
			(stroke
				(width 0.1)
				(type default)
			)
			(layer "F.Fab")
		)
		(pad "1" smd rect
			(at -0.889 0 180)
			(size 1.016 1.27)
			(layers "F.Cu" "F.Mask" "F.Paste")
			(net "SW_P12V_PVCCIN_CPU0_FLT")
		)
		(pad "2" smd rect
			(at 0.889 0 180)
			(size 1.016 1.27)
			(layers "F.Cu" "F.Mask" "F.Paste")
			(net "GND")
		)
	)
	(footprint ""
		(layer "F.Cu")
		(at 225.525838 -220.815916 90)
		(property "Reference" "R995"
			(at 0 0 90)
			(layer "F.SilkS")
			(hide yes)
			(effects
				(font
					(size 1.27 1.27)
				)
			)
		)
		(property "Value" ""
			(at 0 0 90)
			(layer "F.Fab")
			(effects
				(font
					(size 1.27 1.27)
				)
			)
		)
		(duplicate_pad_numbers_are_jumpers no)
		(fp_line
			(start 0.7874 -0.4064)
			(end 0.7874 0.4064)
			(stroke
				(width 0.1524)
				(type default)
			)
			(layer "F.SilkS")
		)
		(fp_line
			(start -0.7874 -0.4064)
			(end 0.7874 -0.4064)
			(stroke
				(width 0.1524)
				(type default)
			)
			(layer "F.SilkS")
		)
		(fp_line
			(start 0.7874 0.4064)
			(end -0.7874 0.4064)
			(stroke
				(width 0.1524)
				(type default)
			)
			(layer "F.SilkS")
		)
		(fp_line
			(start -0.7874 0.4064)
			(end -0.7874 -0.4064)
			(stroke
				(width 0.1524)
				(type default)
			)
			(layer "F.SilkS")
		)
		(fp_line
			(start -0.12065 -0.305054)
			(end -0.12065 -0.2794)
			(stroke
				(width 0.1)
				(type default)
			)
			(layer "F.Fab")
		)
		(fp_line
			(start -0.67945 -0.305054)
			(end -0.12065 -0.305054)
			(stroke
				(width 0.1)
				(type default)
			)
			(layer "F.Fab")
		)
		(fp_line
			(start 0.67945 -0.3048)
			(end 0.67945 0.3048)
			(stroke
				(width 0.1)
				(type default)
			)
			(layer "F.Fab")
		)
		(fp_line
			(start 0.12065 -0.3048)
			(end 0.67945 -0.3048)
			(stroke
				(width 0.1)
				(type default)
			)
			(layer "F.Fab")
		)
		(fp_line
			(start 0.12065 -0.2794)
			(end 0.12065 -0.3048)
			(stroke
				(width 0.1)
				(type default)
			)
			(layer "F.Fab")
		)
		(fp_line
			(start -0.12065 -0.2794)
			(end 0.12065 -0.2794)
			(stroke
				(width 0.1)
				(type default)
			)
			(layer "F.Fab")
		)
		(fp_line
			(start 0.120396 0.2794)
			(end -0.12065 0.2794)
			(stroke
				(width 0.1)
				(type default)
			)
			(layer "F.Fab")
		)
		(fp_line
			(start -0.12065 0.2794)
			(end -0.12065 0.3048)
			(stroke
				(width 0.1)
				(type default)
			)
			(layer "F.Fab")
		)
		(fp_line
			(start 0.67945 0.3048)
			(end 0.120396 0.3048)
			(stroke
				(width 0.1)
				(type default)
			)
			(layer "F.Fab")
		)
		(fp_line
			(start 0.120396 0.3048)
			(end 0.120396 0.2794)
			(stroke
				(width 0.1)
				(type default)
			)
			(layer "F.Fab")
		)
		(fp_line
			(start -0.12065 0.3048)
			(end -0.67945 0.3048)
			(stroke
				(width 0.1)
				(type default)
			)
			(layer "F.Fab")
		)
		(fp_line
			(start -0.67945 0.3048)
			(end -0.67945 -0.305054)
			(stroke
				(width 0.1)
				(type default)
			)
			(layer "F.Fab")
		)
		(pad "1" smd circle
			(at -0.40005 0 90)
			(size 0 0)
			(layers "F.Cu" "F.Mask" "F.Paste")
			(net "SMB_S3M_CPU1_SCL")
		)
		(pad "2" smd circle
			(at 0.40005 0 90)
			(size 0 0)
			(layers "F.Cu" "F.Mask" "F.Paste")
			(net "SMB_S3M_CPU1_R_SCL")
		)
	)
)
